(kicad_pcb
	(version 20241229)
	(generator "pcbnew")
	(generator_version "9.0")
	(general
		(thickness 1.63)
		(legacy_teardrops no)
	)
	(paper "A4")
	(title_block
		(title "CM4 Baseboard")
		(date "2026-01-05")
		(rev "1.1.1")
		(company "Antmicro Ltd")
		(comment 1 "www.antmicro.com")
		(comment 9 "footprints 211-215 of 506")
	)
	(layers
		(0 "F.Cu" signal)
		(4 "In1.Cu" power)
		(6 "In2.Cu" power)
		(8 "In3.Cu" signal)
		(10 "In4.Cu" signal)
		(2 "B.Cu" signal)
		(9 "F.Adhes" user "F.Adhesive")
		(11 "B.Adhes" user "B.Adhesive")
		(13 "F.Paste" user)
		(15 "B.Paste" user)
		(5 "F.SilkS" user "F.Silkscreen")
		(7 "B.SilkS" user "B.Silkscreen")
		(1 "F.Mask" user)
		(3 "B.Mask" user)
		(17 "Dwgs.User" user "User.Drawings")
		(19 "Cmts.User" user "User.Comments")
		(21 "Eco1.User" user "User.Eco1")
		(23 "Eco2.User" user "User.Eco2")
		(25 "Edge.Cuts" user)
		(27 "Margin" user)
		(31 "F.CrtYd" user "F.Courtyard")
		(29 "B.CrtYd" user "B.Courtyard")
		(35 "F.Fab" user)
		(33 "B.Fab" user)
	)
	(footprint "antmicro-footprints:R_0402_1005Metric"
		(layer "F.Cu")
		(at 123.792962 167.8665)
		(descr "Resistor SMD 0402")
		(tags "resistor SMD 0402")
		(property "Reference" "R511"
			(at -3.837514 0.45 0)
			(layer "F.SilkS")
			(effects
				(font
					(size 0.7 0.7)
					(thickness 0.15)
				)
				(justify left bottom)
			)
		)
		(property "Value" "R_10k_0402"
			(at -1.011843 1.772047 0)
			(layer "F.Fab")
			(effects
				(font
					(size 0.7 0.7)
					(thickness 0.15)
				)
				(justify left bottom)
			)
		)
		(property "Datasheet" "https://www.bourns.com/docs/product-datasheets/cr.pdf"
			(at 0 0 0)
			(layer "F.Fab")
			(hide yes)
			(effects
				(font
					(size 1.27 1.27)
					(thickness 0.15)
				)
			)
		)
		(property "Manufacturer" "Bourns"
			(at 0 0 0)
			(unlocked yes)
			(layer "F.Fab")
			(hide yes)
			(effects
				(font
					(size 1 1)
					(thickness 0.15)
				)
			)
		)
		(property "MPN" "CR0402-FX-1002GLF"
			(at 0 0 0)
			(unlocked yes)
			(layer "F.Fab")
			(hide yes)
			(effects
				(font
					(size 1 1)
					(thickness 0.15)
				)
			)
		)
		(property "Val" "10k"
			(at 0 0 0)
			(unlocked yes)
			(layer "F.Fab")
			(hide yes)
			(effects
				(font
					(size 1 1)
					(thickness 0.15)
				)
			)
		)
		(property "License" "Apache-2.0"
			(at 0 0 0)
			(unlocked yes)
			(layer "F.Fab")
			(hide yes)
			(effects
				(font
					(size 1 1)
					(thickness 0.15)
				)
			)
		)
		(property "Author" "Antmicro"
			(at 0 0 0)
			(unlocked yes)
			(layer "F.Fab")
			(hide yes)
			(effects
				(font
					(size 1 1)
					(thickness 0.15)
				)
			)
		)
		(property "Tolerance" "1%"
			(at 0 0 0)
			(unlocked yes)
			(layer "F.Fab")
			(hide yes)
			(effects
				(font
					(size 1 1)
					(thickness 0.15)
				)
			)
		)
		(sheetname "/NVMe & microSD/")
		(sheetfile "nvme-micro-sd.kicad_sch")
		(attr smd)
		(fp_rect
			(start -0.925 -0.47)
			(end 0.925 0.47)
			(stroke
				(width 0.05)
				(type default)
			)
			(fill no)
			(layer "F.CrtYd")
		)
		(fp_rect
			(start -0.5 -0.25)
			(end 0.5 0.25)
			(stroke
				(width 0.15)
				(type solid)
			)
			(fill no)
			(layer "F.Fab")
		)
		(fp_text user "${REFERENCE}"
			(at -0.95 3.168 0)
			(layer "F.Fab")
			(effects
				(font
					(size 0.7 0.7)
					(thickness 0.15)
				)
				(justify left bottom)
			)
		)
		(fp_text user "Author: Antmicro"
			(at -0.95 4.169 0)
			(layer "F.Fab")
			(effects
				(font
					(size 0.7 0.7)
					(thickness 0.15)
				)
				(justify left bottom)
			)
		)
		(fp_text user "License: Apache-2.0"
			(at -0.95 5.169 0)
			(layer "F.Fab")
			(effects
				(font
					(size 0.7 0.7)
					(thickness 0.15)
				)
				(justify left bottom)
			)
		)
		(pad "1" smd roundrect
			(at -0.48 0)
			(size 0.59 0.64)
			(layers "F.Cu" "F.Mask" "F.Paste")
			(roundrect_rratio 0.25)
			(net 9 "+3V3")
			(pintype "passive")
		)
		(pad "2" smd roundrect
			(at 0.48 0)
			(size 0.59 0.64)
			(layers "F.Cu" "F.Mask" "F.Paste")
			(roundrect_rratio 0.25)
			(net 12 "/Compute module/SDIO.D2")
			(pintype "passive")
		)
	)
	(footprint "antmicro-footprints:LED_0603_1608Metric_G"
		(layer "F.Cu")
		(at 117.627962 139.5915 90)
		(descr "LED SMD 0603 Green")
		(tags "LED SMD 0603 Green")
		(property "Reference" "D305"
			(at -3.325 1.54 90)
			(layer "F.SilkS")
			(effects
				(font
					(size 0.7 0.7)
					(thickness 0.15)
				)
				(justify left bottom)
			)
		)
		(property "Value" "LED_G_0603_KP-1608CGCK"
			(at -0.001 1.599 90)
			(layer "F.Fab")
			(effects
				(font
					(size 0.7 0.7)
					(thickness 0.15)
				)
				(justify left bottom)
			)
		)
		(property "Datasheet" "http://www.kingbright.com/attachments/file/psearch//000/00/00/KP-1608CGCK(Ver.23B).pdf"
			(at 0 0 90)
			(layer "F.Fab")
			(hide yes)
			(effects
				(font
					(size 1.27 1.27)
					(thickness 0.15)
				)
			)
		)
		(property "MPN" "KP-1608CGCK"
			(at 0 0 90)
			(unlocked yes)
			(layer "F.Fab")
			(hide yes)
			(effects
				(font
					(size 1 1)
					(thickness 0.15)
				)
			)
		)
		(property "Manufacturer" "Kingbright"
			(at 0 0 90)
			(unlocked yes)
			(layer "F.Fab")
			(hide yes)
			(effects
				(font
					(size 1 1)
					(thickness 0.15)
				)
			)
		)
		(property "Color" "Green"
			(at 0 0 90)
			(unlocked yes)
			(layer "F.Fab")
			(hide yes)
			(effects
				(font
					(size 1 1)
					(thickness 0.15)
				)
			)
		)
		(property "Author" "Antmicro"
			(at 0 0 90)
			(unlocked yes)
			(layer "F.Fab")
			(hide yes)
			(effects
				(font
					(size 1 1)
					(thickness 0.15)
				)
			)
		)
		(property "License" "Apache-2.0"
			(at 0 0 90)
			(unlocked yes)
			(layer "F.Fab")
			(hide yes)
			(effects
				(font
					(size 1 1)
					(thickness 0.15)
				)
			)
		)
		(sheetname "/Supply/")
		(sheetfile "supply.kicad_sch")
		(attr smd)
		(fp_line
			(start 0.22 -0.35)
			(end -0.22 -0.35)
			(stroke
				(width 0.15)
				(type solid)
			)
			(layer "F.SilkS")
		)
		(fp_line
			(start -1.18 -0.319)
			(end -1.18 0.321)
			(stroke
				(width 0.15)
				(type solid)
			)
			(layer "F.SilkS")
		)
		(fp_line
			(start 0.105328 0.001008)
			(end 0.24 0.001)
			(stroke
				(width 0.1)
				(type solid)
			)
			(layer "F.SilkS")
		)
		(fp_line
			(start -0.094672 0.001008)
			(end 0.105328 -0.198992)
			(stroke
				(width 0.1)
				(type solid)
			)
			(layer "F.SilkS")
		)
		(fp_line
			(start -0.094672 0.001008)
			(end -0.24 0.001008)
			(stroke
				(width 0.1)
				(type solid)
			)
			(layer "F.SilkS")
		)
		(fp_line
			(start 0.105328 0.201008)
			(end 0.105328 -0.198992)
			(stroke
				(width 0.1)
				(type solid)
			)
			(layer "F.SilkS")
		)
		(fp_line
			(start 0.105328 0.201008)
			(end -0.094672 0.001008)
			(stroke
				(width 0.1)
				(type solid)
			)
			(layer "F.SilkS")
		)
		(fp_line
			(start -0.094672 0.201008)
			(end -0.094672 -0.198992)
			(stroke
				(width 0.1)
				(type solid)
			)
			(layer "F.SilkS")
		)
		(fp_line
			(start 0.22 0.35)
			(end -0.22 0.35)
			(stroke
				(width 0.15)
				(type solid)
			)
			(layer "F.SilkS")
		)
		(fp_rect
			(start 1.25 0.65)
			(end -1.25 -0.65)
			(stroke
				(width 0.05)
				(type solid)
			)
			(fill no)
			(layer "F.CrtYd")
		)
		(fp_line
			(start 0.201 -0.202)
			(end -0.101 0)
			(stroke
				(width 0.15)
				(type solid)
			)
			(layer "F.Fab")
		)
		(fp_line
			(start -0.199 -0.202)
			(end -0.199 0.1)
			(stroke
				(width 0.15)
				(type solid)
			)
			(layer "F.Fab")
		)
		(fp_line
			(start 0.599 0)
			(end 0.201 0)
			(stroke
				(width 0.15)
				(type solid)
			)
			(layer "F.Fab")
		)
		(fp_line
			(start 0.201 0)
			(end 0.201 -0.202)
			(stroke
				(width 0.15)
				(type solid)
			)
			(layer "F.Fab")
		)
		(fp_line
			(start -0.101 0)
			(end 0.201 0.2)
			(stroke
				(width 0.15)
				(type solid)
			)
			(layer "F.Fab")
		)
		(fp_line
			(start -0.199 0)
			(end -0.597 0)
			(stroke
				(width 0.15)
				(type solid)
			)
			(layer "F.Fab")
		)
		(fp_line
			(start 0.201 0.2)
			(end 0.201 0)
			(stroke
				(width 0.15)
				(type solid)
			)
			(layer "F.Fab")
		)
		(fp_line
			(start -0.199 0.2)
			(end -0.199 0.1)
			(stroke
				(width 0.15)
				(type solid)
			)
			(layer "F.Fab")
		)
		(fp_rect
			(start 0.848 0.4)
			(end -0.85 -0.402)
			(stroke
				(width 0.15)
				(type solid)
			)
			(fill no)
			(layer "F.Fab")
		)
		(fp_text user "${REFERENCE}"
			(at -1.4224 5.999 90)
			(layer "F.Fab")
			(effects
				(font
					(size 0.7 0.7)
					(thickness 0.15)
				)
				(justify left bottom)
			)
		)
		(fp_text user "License: Apache-2.0"
			(at -1.4224 3.599 90)
			(layer "F.Fab")
			(effects
				(font
					(size 0.7 0.7)
					(thickness 0.15)
				)
				(justify left bottom)
			)
		)
		(fp_text user "Author: Antmicro"
			(at -1.4224 4.799 90)
			(layer "F.Fab")
			(effects
				(font
					(size 0.7 0.7)
					(thickness 0.15)
				)
				(justify left bottom)
			)
		)
		(pad "1" smd roundrect
			(at -0.7 0 270)
			(size 0.8 1)
			(layers "F.Cu" "F.Mask" "F.Paste")
			(roundrect_rratio 0.2)
			(net 3 "GND")
			(pinfunction "C")
			(pintype "passive")
		)
		(pad "2" smd roundrect
			(at 0.7 0 270)
			(size 0.8 1)
			(layers "F.Cu" "F.Mask" "F.Paste")
			(roundrect_rratio 0.2)
			(net 475 "Net-(D305-A)")
			(pinfunction "A")
			(pintype "passive")
		)
	)
	(footprint "antmicro-footprints:R_0402_1005Metric"
		(layer "F.Cu")
		(at 99.717962 147.5665 180)
		(descr "Resistor SMD 0402")
		(tags "resistor SMD 0402")
		(property "Reference" "R931"
			(at -3.6 -0.7 0)
			(layer "F.SilkS")
			(effects
				(font
					(size 0.7 0.7)
					(thickness 0.15)
				)
				(justify right bottom)
			)
		)
		(property "Value" "R_0R_0402"
			(at -1.011843 1.772047 0)
			(layer "F.Fab")
			(effects
				(font
					(size 0.7 0.7)
					(thickness 0.15)
				)
				(justify right bottom)
			)
		)
		(property "Datasheet" "https://industrial.panasonic.com/cdbs/www-data/pdf/RDA0000/AOA0000C301.pdf"
			(at 0 0 180)
			(layer "F.Fab")
			(hide yes)
			(effects
				(font
					(size 1.27 1.27)
					(thickness 0.15)
				)
			)
		)
		(property "Manufacturer" "Panasonic"
			(at 0 0 180)
			(unlocked yes)
			(layer "F.Fab")
			(hide yes)
			(effects
				(font
					(size 1 1)
					(thickness 0.15)
				)
			)
		)
		(property "MPN" "ERJ2GE0R00X"
			(at 0 0 180)
			(unlocked yes)
			(layer "F.Fab")
			(hide yes)
			(effects
				(font
					(size 1 1)
					(thickness 0.15)
				)
			)
		)
		(property "Val" "0R"
			(at 0 0 180)
			(unlocked yes)
			(layer "F.Fab")
			(hide yes)
			(effects
				(font
					(size 1 1)
					(thickness 0.15)
				)
			)
		)
		(property "License" "Apache-2.0"
			(at 0 0 180)
			(unlocked yes)
			(layer "F.Fab")
			(hide yes)
			(effects
				(font
					(size 1 1)
					(thickness 0.15)
				)
			)
		)
		(property "Author" "Antmicro"
			(at 0 0 180)
			(unlocked yes)
			(layer "F.Fab")
			(hide yes)
			(effects
				(font
					(size 1 1)
					(thickness 0.15)
				)
			)
		)
		(property "Tolerance" "~"
			(at 0 0 180)
			(unlocked yes)
			(layer "F.Fab")
			(hide yes)
			(effects
				(font
					(size 1 1)
					(thickness 0.15)
				)
			)
		)
		(property "Current" "1A"
			(at 0 0 180)
			(unlocked yes)
			(layer "F.Fab")
			(hide yes)
			(effects
				(font
					(size 1 1)
					(thickness 0.15)
				)
			)
		)
		(sheetname "/USB/")
		(sheetfile "usb.kicad_sch")
		(attr smd)
		(fp_rect
			(start -0.925 -0.47)
			(end 0.925 0.47)
			(stroke
				(width 0.05)
				(type default)
			)
			(fill no)
			(layer "F.CrtYd")
		)
		(fp_rect
			(start -0.5 -0.25)
			(end 0.5 0.25)
			(stroke
				(width 0.15)
				(type solid)
			)
			(fill no)
			(layer "F.Fab")
		)
		(fp_text user "${REFERENCE}"
			(at -0.95 3.168 180)
			(layer "F.Fab")
			(effects
				(font
					(size 0.7 0.7)
					(thickness 0.15)
				)
				(justify left bottom)
			)
		)
		(fp_text user "License: Apache-2.0"
			(at -0.95 5.169 180)
			(layer "F.Fab")
			(effects
				(font
					(size 0.7 0.7)
					(thickness 0.15)
				)
				(justify left bottom)
			)
		)
		(fp_text user "Author: Antmicro"
			(at -0.95 4.169 180)
			(layer "F.Fab")
			(effects
				(font
					(size 0.7 0.7)
					(thickness 0.15)
				)
				(justify left bottom)
			)
		)
		(pad "1" smd roundrect
			(at -0.48 0 180)
			(size 0.59 0.64)
			(layers "F.Cu" "F.Mask" "F.Paste")
			(roundrect_rratio 0.25)
			(net 490 "Net-(Q905-G)")
			(pintype "passive")
		)
		(pad "2" smd roundrect
			(at 0.48 0 180)
			(size 0.59 0.64)
			(layers "F.Cu" "F.Mask" "F.Paste")
			(roundrect_rratio 0.25)
			(net 463 "/USB/I2C_EN")
			(pintype "passive")
		)
	)
	(footprint "antmicro-footprints:R_0402_1005Metric"
		(layer "F.Cu")
		(at 77.65 170.0665 -90)
		(descr "Resistor SMD 0402")
		(tags "resistor SMD 0402")
		(property "Reference" "R242"
			(at -3.98 -11.56 90)
			(layer "F.SilkS")
			(effects
				(font
					(size 0.7 0.7)
					(thickness 0.15)
				)
				(justify right bottom)
			)
		)
		(property "Value" "R_200R_0402"
			(at -1.011843 1.772047 90)
			(layer "F.Fab")
			(effects
				(font
					(size 0.7 0.7)
					(thickness 0.15)
				)
				(justify right bottom)
			)
		)
		(property "Datasheet" "https://www.bourns.com/docs/product-datasheets/cr.pdf"
			(at 0 0 270)
			(layer "F.Fab")
			(hide yes)
			(effects
				(font
					(size 1.27 1.27)
					(thickness 0.15)
				)
			)
		)
		(property "Manufacturer" "Bourns"
			(at 0 0 270)
			(unlocked yes)
			(layer "F.Fab")
			(hide yes)
			(effects
				(font
					(size 1 1)
					(thickness 0.15)
				)
			)
		)
		(property "MPN" "CR0402-FX-2000GLF"
			(at 0 0 270)
			(unlocked yes)
			(layer "F.Fab")
			(hide yes)
			(effects
				(font
					(size 1 1)
					(thickness 0.15)
				)
			)
		)
		(property "Val" "200R"
			(at 0 0 270)
			(unlocked yes)
			(layer "F.Fab")
			(hide yes)
			(effects
				(font
					(size 1 1)
					(thickness 0.15)
				)
			)
		)
		(property "License" "Apache-2.0"
			(at 0 0 270)
			(unlocked yes)
			(layer "F.Fab")
			(hide yes)
			(effects
				(font
					(size 1 1)
					(thickness 0.15)
				)
			)
		)
		(property "Author" "Antmicro"
			(at 0 0 270)
			(unlocked yes)
			(layer "F.Fab")
			(hide yes)
			(effects
				(font
					(size 1 1)
					(thickness 0.15)
				)
			)
		)
		(property "Tolerance" "1%"
			(at 0 0 270)
			(unlocked yes)
			(layer "F.Fab")
			(hide yes)
			(effects
				(font
					(size 1 1)
					(thickness 0.15)
				)
			)
		)
		(sheetname "/Compute module/")
		(sheetfile "compute-module.kicad_sch")
		(attr smd exclude_from_pos_files exclude_from_bom dnp)
		(fp_rect
			(start -0.925 -0.47)
			(end 0.925 0.47)
			(stroke
				(width 0.05)
				(type default)
			)
			(fill no)
			(layer "F.CrtYd")
		)
		(fp_rect
			(start -0.5 -0.25)
			(end 0.5 0.25)
			(stroke
				(width 0.15)
				(type solid)
			)
			(fill no)
			(layer "F.Fab")
		)
		(fp_text user "${REFERENCE}"
			(at -0.95 3.168 270)
			(layer "F.Fab")
			(effects
				(font
					(size 0.7 0.7)
					(thickness 0.15)
				)
				(justify left bottom)
			)
		)
		(fp_text user "License: Apache-2.0"
			(at -0.95 5.169 270)
			(layer "F.Fab")
			(effects
				(font
					(size 0.7 0.7)
					(thickness 0.15)
				)
				(justify left bottom)
			)
		)
		(fp_text user "Author: Antmicro"
			(at -0.95 4.169 270)
			(layer "F.Fab")
			(effects
				(font
					(size 0.7 0.7)
					(thickness 0.15)
				)
				(justify left bottom)
			)
		)
		(pad "1" smd roundrect
			(at -0.48 0 270)
			(size 0.59 0.64)
			(layers "F.Cu" "F.Mask" "F.Paste")
			(roundrect_rratio 0.25)
			(net 276 "Net-(U204-GPA3)")
			(pintype "passive")
		)
		(pad "2" smd roundrect
			(at 0.48 0 270)
			(size 0.59 0.64)
			(layers "F.Cu" "F.Mask" "F.Paste")
			(roundrect_rratio 0.25)
			(net 469 "Net-(D207-C)")
			(pintype "passive")
		)
	)
	(footprint "antmicro-footprints:TP_SMD_0.75mm"
		(layer "F.Cu")
		(at 76 162.9565 180)
		(property "Reference" "TP206"
			(at 8.55 -0.1935 0)
			(layer "F.SilkS")
			(effects
				(font
					(size 0.7 0.7)
					(thickness 0.15)
				)
				(justify right bottom)
			)
		)
		(property "Value" "TP_0.75mm_SMD"
			(at 0 1.2 0)
			(layer "F.Fab")
			(effects
				(font
					(size 0.7 0.7)
					(thickness 0.15)
				)
				(justify right bottom)
			)
		)
		(property "Author" "Antmicro"
			(at 0 0 180)
			(unlocked yes)
			(layer "F.Fab")
			(hide yes)
			(effects
				(font
					(size 1 1)
					(thickness 0.15)
				)
			)
		)
		(property "License" "Apache-2.0"
			(at 0 0 180)
			(unlocked yes)
			(layer "F.Fab")
			(hide yes)
			(effects
				(font
					(size 1 1)
					(thickness 0.15)
				)
			)
		)
		(property "MPN" ""
			(at 0 0 180)
			(unlocked yes)
			(layer "F.Fab")
			(hide yes)
			(effects
				(font
					(size 1 1)
					(thickness 0.15)
				)
			)
		)
		(property "Manufacturer" ""
			(at 0 0 180)
			(unlocked yes)
			(layer "F.Fab")
			(hide yes)
			(effects
				(font
					(size 1 1)
					(thickness 0.15)
				)
			)
		)
		(sheetname "/Compute module/")
		(sheetfile "compute-module.kicad_sch")
		(attr exclude_from_pos_files exclude_from_bom)
		(fp_circle
			(center 0 0)
			(end 0.475 0)
			(stroke
				(width 0.05)
				(type default)
			)
			(fill no)
			(layer "F.CrtYd")
		)
		(fp_text user "${REFERENCE}"
			(at -0.4 2.7 180)
			(layer "F.Fab")
			(effects
				(font
					(size 0.7 0.7)
					(thickness 0.15)
				)
				(justify left bottom)
			)
		)
		(fp_text user "Author: Antmicro"
			(at -0.4 3.901 180)
			(layer "F.Fab")
			(effects
				(font
					(size 0.7 0.7)
					(thickness 0.15)
				)
				(justify left bottom)
			)
		)
		(fp_text user "License: Apache-2.0"
			(at -0.4 5.101 180)
			(layer "F.Fab")
			(effects
				(font
					(size 0.7 0.7)
					(thickness 0.15)
				)
				(justify left bottom)
			)
		)
		(pad "1" smd circle
			(at 0 0 180)
			(size 0.75 0.75)
			(layers "F.Cu" "F.Mask")
			(net 248 "/Compute module/BT_nDis")
			(pinfunction "1")
			(pintype "passive")
		)
	)
)
